(kicad_pcb
	(version 20260206)
	(generator "pcbnew")
	(generator_version "10.0")
	(general
		(thickness 1.6)
		(legacy_teardrops no)
	)
	(paper "A4")
	(title_block
		(title "03242023_DA0F0TMBIJ0_F0T_Motherboard_J_brd_V01_OCP.brd")
		(comment 1 "Grand Teton / footprints 5801-5805 of 6105")
	)
	(layers
		(0 "F.Cu" signal "TOP")
		(4 "In1.Cu" signal "GND")
		(6 "In2.Cu" signal "IN1")
		(8 "In3.Cu" signal "GND1")
		(10 "In4.Cu" signal "IN2")
		(12 "In5.Cu" signal "GND2")
		(14 "In6.Cu" signal "IN3")
		(16 "In7.Cu" signal "GND3")
		(18 "In8.Cu" signal "VCC")
		(20 "In9.Cu" signal "VCC1")
		(22 "In10.Cu" signal "GND4")
		(24 "In11.Cu" signal "IN4")
		(26 "In12.Cu" signal "GND5")
		(28 "In13.Cu" signal "IN5")
		(30 "In14.Cu" signal "GND6")
		(32 "In15.Cu" signal "IN6")
		(34 "In16.Cu" signal "GND7")
		(2 "B.Cu" signal "BOTTOM")
		(9 "F.Adhes" user "F.Adhesive")
		(11 "B.Adhes" user "B.Adhesive")
		(13 "F.Paste" user "Package Geometry/Pastemask Top")
		(15 "B.Paste" user "Package Geometry/Pastemask Bottom")
		(5 "F.SilkS" user "Ref Des/Silkscreen Top")
		(7 "B.SilkS" user "Ref Des/Silkscreen Bottom")
		(1 "F.Mask" user "Board Geometry/Soldermask Top")
		(3 "B.Mask" user "Board Geometry/Soldermask Bottom")
		(17 "Dwgs.User" user "User.Drawings")
		(19 "Cmts.User" user "User.Comments")
		(21 "Eco1.User" user "User.Eco1")
		(23 "Eco2.User" user "User.Eco2")
		(25 "Edge.Cuts" user "Board Geometry/Outline")
		(27 "Margin" user)
		(31 "F.CrtYd" user "Package Geometry/Place Bound Top")
		(29 "B.CrtYd" user "Package Geometry/Place Bound Bottom")
		(35 "F.Fab" user "Ref Des/Assembly Top")
		(33 "B.Fab" user "Ref Des/Assembly Bottom")
	)
	(footprint ""
		(layer "B.Cu")
		(at 511.924808 -303.58588 -90)
		(property "Reference" "X27"
			(at 3.47472 2.673858 270)
			(unlocked yes)
			(layer "B.SilkS")
			(effects
				(font
					(size 0.7874 0.5842)
					(thickness 0.1524)
				)
				(justify left mirror)
			)
		)
		(property "Value" ""
			(at 0 0 90)
			(layer "B.Fab")
			(effects
				(font
					(size 1.27 1.27)
				)
				(justify mirror)
			)
		)
		(property "Device Type" "TP_TDR_4P_FTS_TH-TP_TDR_4P_DIPA"
			(at -1.30175 1.27 180)
			(unlocked yes)
			(layer "B.Fab")
			(hide yes)
			(effects
				(font
					(size 0.635 0.4064)
					(thickness 0.1524)
				)
				(justify mirror)
			)
		)
		(property "User Part Number" "N_A"
			(at -1.30175 1.27 180)
			(unlocked yes)
			(layer "Cmts.User")
			(hide yes)
			(effects
				(font
					(size 0.635 0.4064)
					(thickness 0.1524)
				)
				(justify mirror)
			)
		)
		(duplicate_pad_numbers_are_jumpers no)
		(fp_line
			(start -2.54 3.81)
			(end -2.54 3.6703)
			(stroke
				(width 0.1524)
				(type default)
			)
			(layer "B.SilkS")
		)
		(fp_line
			(start 0 3.81)
			(end -2.54 3.81)
			(stroke
				(width 0.1524)
				(type default)
			)
			(layer "B.SilkS")
		)
		(fp_line
			(start 0 3.175)
			(end 0 3.81)
			(stroke
				(width 0.1524)
				(type default)
			)
			(layer "B.SilkS")
		)
		(fp_line
			(start -2.54 1.4097)
			(end -2.54 1.1303)
			(stroke
				(width 0.1524)
				(type default)
			)
			(layer "B.SilkS")
		)
		(fp_line
			(start 0 0.635)
			(end 0 1.905)
			(stroke
				(width 0.1524)
				(type default)
			)
			(layer "B.SilkS")
		)
		(fp_line
			(start -2.54 -1.1303)
			(end -2.54 -1.27)
			(stroke
				(width 0.1524)
				(type default)
			)
			(layer "B.SilkS")
		)
		(fp_line
			(start -2.54 -1.27)
			(end 0 -1.27)
			(stroke
				(width 0.1524)
				(type default)
			)
			(layer "B.SilkS")
		)
		(fp_line
			(start 0 -1.27)
			(end 0 -0.635)
			(stroke
				(width 0.1524)
				(type default)
			)
			(layer "B.SilkS")
		)
		(fp_poly
			(pts
				(xy 3.001518 -0.804164) (xy 3.001518 0.719836) (xy 1.477518 -0.042164)
			)
			(stroke
				(width 0)
				(type default)
			)
			(fill yes)
			(layer "B.SilkS")
		)
		(fp_line
			(start -2.54 3.81)
			(end -2.54 -1.27)
			(stroke
				(width 0.1)
				(type default)
			)
			(layer "B.Fab")
		)
		(fp_line
			(start 0 3.81)
			(end -2.54 3.81)
			(stroke
				(width 0.1)
				(type default)
			)
			(layer "B.Fab")
		)
		(fp_line
			(start -2.54 -1.27)
			(end 0 -1.27)
			(stroke
				(width 0.1)
				(type default)
			)
			(layer "B.Fab")
		)
		(fp_line
			(start 0 -1.27)
			(end 0 3.81)
			(stroke
				(width 0.1)
				(type default)
			)
			(layer "B.Fab")
		)
		(fp_poly
			(pts
				(xy 0.761746 0) (xy 2.285746 -0.762) (xy 2.285746 0.762)
			)
			(stroke
				(width 0)
				(type default)
			)
			(fill yes)
			(layer "B.Fab")
		)
		(pad "1" thru_hole circle
			(at 0 0 90)
			(size 1.0033 1.0033)
			(drill 0.249936)
			(layers "*.Cu" "*.Mask")
			(remove_unused_layers no)
			(net "TDR_DIFF_85_IN5_DN")
			(clearance 0.10795)
			(padstack
				(mode front_inner_back)
				(layer "Inner"
					(shape circle)
					(size 0.8001 0.8001)
					(clearance 0.1524)
				)
				(layer "B.Cu"
					(shape circle)
					(size 1.0033 1.0033)
					(thermal_gap 0.10795)
					(clearance 0.10795)
				)
			)
		)
		(pad "2" thru_hole circle
			(at -2.54 0 90)
			(size 1.9939 1.9939)
			(drill 0.249936)
			(layers "*.Cu" "*.Mask")
			(remove_unused_layers no)
			(net "T1_GND")
			(clearance 0.10795)
			(padstack
				(mode front_inner_back)
				(layer "Inner"
					(shape circle)
					(size 0.8001 0.8001)
					(clearance 0.1524)
				)
				(layer "B.Cu"
					(shape circle)
					(size 1.9939 1.9939)
					(thermal_gap 0.10795)
					(clearance 0.10795)
				)
			)
		)
		(pad "3" thru_hole circle
			(at -2.54 2.54 90)
			(size 1.9939 1.9939)
			(drill 0.249936)
			(layers "*.Cu" "*.Mask")
			(remove_unused_layers no)
			(net "T1_GND")
			(clearance 0.10795)
			(padstack
				(mode front_inner_back)
				(layer "Inner"
					(shape circle)
					(size 0.8001 0.8001)
					(clearance 0.1524)
				)
				(layer "B.Cu"
					(shape circle)
					(size 1.9939 1.9939)
					(thermal_gap 0.10795)
					(clearance 0.10795)
				)
			)
		)
		(pad "4" thru_hole circle
			(at 0 2.54 90)
			(size 1.0033 1.0033)
			(drill 0.249936)
			(layers "*.Cu" "*.Mask")
			(remove_unused_layers no)
			(net "TDR_DIFF_85_IN5_DP")
			(clearance 0.10795)
			(padstack
				(mode front_inner_back)
				(layer "Inner"
					(shape circle)
					(size 0.8001 0.8001)
					(clearance 0.1524)
				)
				(layer "B.Cu"
					(shape circle)
					(size 1.0033 1.0033)
					(thermal_gap 0.10795)
					(clearance 0.10795)
				)
			)
		)
	)
	(footprint ""
		(layer "B.Cu")
		(at 36.60648 -344.757248 -90)
		(property "Reference" "PR4241"
			(at 0 0 90)
			(layer "B.SilkS")
			(hide yes)
			(effects
				(font
					(size 1.27 1.27)
				)
				(justify mirror)
			)
		)
		(property "Value" ""
			(at 0 0 90)
			(layer "B.Fab")
			(effects
				(font
					(size 1.27 1.27)
				)
				(justify mirror)
			)
		)
		(duplicate_pad_numbers_are_jumpers no)
		(fp_line
			(start -0.7874 0.4064)
			(end 0.7874 0.4064)
			(stroke
				(width 0.1524)
				(type default)
			)
			(layer "B.SilkS")
		)
		(fp_line
			(start 0.7874 0.4064)
			(end 0.7874 -0.4064)
			(stroke
				(width 0.1524)
				(type default)
			)
			(layer "B.SilkS")
		)
		(fp_line
			(start -0.7874 -0.4064)
			(end -0.7874 0.4064)
			(stroke
				(width 0.1524)
				(type default)
			)
			(layer "B.SilkS")
		)
		(fp_line
			(start 0.7874 -0.4064)
			(end -0.7874 -0.4064)
			(stroke
				(width 0.1524)
				(type default)
			)
			(layer "B.SilkS")
		)
		(fp_line
			(start -0.67945 0.3048)
			(end -0.120396 0.3048)
			(stroke
				(width 0.1)
				(type default)
			)
			(layer "B.Fab")
		)
		(fp_line
			(start -0.120396 0.3048)
			(end -0.120396 0.2794)
			(stroke
				(width 0.1)
				(type default)
			)
			(layer "B.Fab")
		)
		(fp_line
			(start 0.12065 0.3048)
			(end 0.67945 0.3048)
			(stroke
				(width 0.1)
				(type default)
			)
			(layer "B.Fab")
		)
		(fp_line
			(start 0.67945 0.3048)
			(end 0.67945 -0.305054)
			(stroke
				(width 0.1)
				(type default)
			)
			(layer "B.Fab")
		)
		(fp_line
			(start -0.120396 0.2794)
			(end 0.12065 0.2794)
			(stroke
				(width 0.1)
				(type default)
			)
			(layer "B.Fab")
		)
		(fp_line
			(start 0.12065 0.2794)
			(end 0.12065 0.3048)
			(stroke
				(width 0.1)
				(type default)
			)
			(layer "B.Fab")
		)
		(fp_line
			(start -0.12065 -0.2794)
			(end -0.12065 -0.3048)
			(stroke
				(width 0.1)
				(type default)
			)
			(layer "B.Fab")
		)
		(fp_line
			(start 0.12065 -0.2794)
			(end -0.12065 -0.2794)
			(stroke
				(width 0.1)
				(type default)
			)
			(layer "B.Fab")
		)
		(fp_line
			(start -0.67945 -0.3048)
			(end -0.67945 0.3048)
			(stroke
				(width 0.1)
				(type default)
			)
			(layer "B.Fab")
		)
		(fp_line
			(start -0.12065 -0.3048)
			(end -0.67945 -0.3048)
			(stroke
				(width 0.1)
				(type default)
			)
			(layer "B.Fab")
		)
		(fp_line
			(start 0.12065 -0.305054)
			(end 0.12065 -0.2794)
			(stroke
				(width 0.1)
				(type default)
			)
			(layer "B.Fab")
		)
		(fp_line
			(start 0.67945 -0.305054)
			(end 0.12065 -0.305054)
			(stroke
				(width 0.1)
				(type default)
			)
			(layer "B.Fab")
		)
		(pad "1" smd circle
			(at 0.40005 0 90)
			(size 0 0)
			(layers "B.Cu" "B.Mask" "B.Paste")
			(net "PVCCFA_EHV_FIVRA_CPU1")
		)
		(pad "2" smd circle
			(at -0.40005 0 90)
			(size 0 0)
			(layers "B.Cu" "B.Mask" "B.Paste")
			(net "GND")
		)
	)
	(footprint ""
		(layer "B.Cu")
		(at 8.153146 -318.25311 180)
		(property "Reference" "R3897"
			(at 0 0 0)
			(layer "B.SilkS")
			(hide yes)
			(effects
				(font
					(size 1.27 1.27)
				)
				(justify mirror)
			)
		)
		(property "Value" ""
			(at 0 0 0)
			(layer "B.Fab")
			(effects
				(font
					(size 1.27 1.27)
				)
				(justify mirror)
			)
		)
		(duplicate_pad_numbers_are_jumpers no)
		(fp_line
			(start 0.7874 0.4064)
			(end 0.7874 -0.4064)
			(stroke
				(width 0.1524)
				(type default)
			)
			(layer "B.SilkS")
		)
		(fp_line
			(start 0.7874 -0.4064)
			(end -0.7874 -0.4064)
			(stroke
				(width 0.1524)
				(type default)
			)
			(layer "B.SilkS")
		)
		(fp_line
			(start -0.7874 0.4064)
			(end 0.7874 0.4064)
			(stroke
				(width 0.1524)
				(type default)
			)
			(layer "B.SilkS")
		)
		(fp_line
			(start -0.7874 -0.4064)
			(end -0.7874 0.4064)
			(stroke
				(width 0.1524)
				(type default)
			)
			(layer "B.SilkS")
		)
		(fp_line
			(start 0.67945 0.3048)
			(end 0.67945 -0.305054)
			(stroke
				(width 0.1)
				(type default)
			)
			(layer "B.Fab")
		)
		(fp_line
			(start 0.67945 -0.305054)
			(end 0.12065 -0.305054)
			(stroke
				(width 0.1)
				(type default)
			)
			(layer "B.Fab")
		)
		(fp_line
			(start 0.12065 0.3048)
			(end 0.67945 0.3048)
			(stroke
				(width 0.1)
				(type default)
			)
			(layer "B.Fab")
		)
		(fp_line
			(start 0.12065 0.2794)
			(end 0.12065 0.3048)
			(stroke
				(width 0.1)
				(type default)
			)
			(layer "B.Fab")
		)
		(fp_line
			(start 0.12065 -0.2794)
			(end -0.12065 -0.2794)
			(stroke
				(width 0.1)
				(type default)
			)
			(layer "B.Fab")
		)
		(fp_line
			(start 0.12065 -0.305054)
			(end 0.12065 -0.2794)
			(stroke
				(width 0.1)
				(type default)
			)
			(layer "B.Fab")
		)
		(fp_line
			(start -0.120396 0.3048)
			(end -0.120396 0.2794)
			(stroke
				(width 0.1)
				(type default)
			)
			(layer "B.Fab")
		)
		(fp_line
			(start -0.120396 0.2794)
			(end 0.12065 0.2794)
			(stroke
				(width 0.1)
				(type default)
			)
			(layer "B.Fab")
		)
		(fp_line
			(start -0.12065 -0.2794)
			(end -0.12065 -0.3048)
			(stroke
				(width 0.1)
				(type default)
			)
			(layer "B.Fab")
		)
		(fp_line
			(start -0.12065 -0.3048)
			(end -0.67945 -0.3048)
			(stroke
				(width 0.1)
				(type default)
			)
			(layer "B.Fab")
		)
		(fp_line
			(start -0.67945 0.3048)
			(end -0.120396 0.3048)
			(stroke
				(width 0.1)
				(type default)
			)
			(layer "B.Fab")
		)
		(fp_line
			(start -0.67945 -0.3048)
			(end -0.67945 0.3048)
			(stroke
				(width 0.1)
				(type default)
			)
			(layer "B.Fab")
		)
		(pad "1" smd circle
			(at 0.40005 0)
			(size 0 0)
			(layers "B.Cu" "B.Mask" "B.Paste")
			(net "I3C_SPD_DDRABCD_CPU1_LVC1_SCL_6")
		)
		(pad "2" smd circle
			(at -0.40005 0)
			(size 0 0)
			(layers "B.Cu" "B.Mask" "B.Paste")
			(net "I3C_SPD_DDRABCD_CPU1_LVC1_SCL")
		)
	)
	(footprint ""
		(layer "B.Cu")
		(at 429.397414 -319.263776 180)
		(property "Reference" "C32"
			(at 0 0 0)
			(layer "B.SilkS")
			(hide yes)
			(effects
				(font
					(size 1.27 1.27)
				)
				(justify mirror)
			)
		)
		(property "Value" ""
			(at 0 0 0)
			(layer "B.Fab")
			(effects
				(font
					(size 1.27 1.27)
				)
				(justify mirror)
			)
		)
		(duplicate_pad_numbers_are_jumpers no)
		(fp_line
			(start 0.7874 0.4064)
			(end 0.7874 -0.4064)
			(stroke
				(width 0.1524)
				(type default)
			)
			(layer "B.SilkS")
		)
		(fp_line
			(start 0.7874 -0.4064)
			(end -0.7874 -0.4064)
			(stroke
				(width 0.1524)
				(type default)
			)
			(layer "B.SilkS")
		)
		(fp_line
			(start -0.7874 0.4064)
			(end 0.7874 0.4064)
			(stroke
				(width 0.1524)
				(type default)
			)
			(layer "B.SilkS")
		)
		(fp_line
			(start -0.7874 -0.4064)
			(end -0.7874 0.4064)
			(stroke
				(width 0.1524)
				(type default)
			)
			(layer "B.SilkS")
		)
		(fp_line
			(start 0.67945 0.3048)
			(end 0.67945 -0.305054)
			(stroke
				(width 0.1)
				(type default)
			)
			(layer "B.Fab")
		)
		(fp_line
			(start 0.67945 -0.305054)
			(end 0.12065 -0.305054)
			(stroke
				(width 0.1)
				(type default)
			)
			(layer "B.Fab")
		)
		(fp_line
			(start 0.12065 0.3048)
			(end 0.67945 0.3048)
			(stroke
				(width 0.1)
				(type default)
			)
			(layer "B.Fab")
		)
		(fp_line
			(start 0.12065 0.2794)
			(end 0.12065 0.3048)
			(stroke
				(width 0.1)
				(type default)
			)
			(layer "B.Fab")
		)
		(fp_line
			(start 0.12065 -0.2794)
			(end -0.12065 -0.2794)
			(stroke
				(width 0.1)
				(type default)
			)
			(layer "B.Fab")
		)
		(fp_line
			(start 0.12065 -0.305054)
			(end 0.12065 -0.2794)
			(stroke
				(width 0.1)
				(type default)
			)
			(layer "B.Fab")
		)
		(fp_line
			(start -0.120396 0.3048)
			(end -0.120396 0.2794)
			(stroke
				(width 0.1)
				(type default)
			)
			(layer "B.Fab")
		)
		(fp_line
			(start -0.120396 0.2794)
			(end 0.12065 0.2794)
			(stroke
				(width 0.1)
				(type default)
			)
			(layer "B.Fab")
		)
		(fp_line
			(start -0.12065 -0.2794)
			(end -0.12065 -0.3048)
			(stroke
				(width 0.1)
				(type default)
			)
			(layer "B.Fab")
		)
		(fp_line
			(start -0.12065 -0.3048)
			(end -0.67945 -0.3048)
			(stroke
				(width 0.1)
				(type default)
			)
			(layer "B.Fab")
		)
		(fp_line
			(start -0.67945 0.3048)
			(end -0.120396 0.3048)
			(stroke
				(width 0.1)
				(type default)
			)
			(layer "B.Fab")
		)
		(fp_line
			(start -0.67945 -0.3048)
			(end -0.67945 0.3048)
			(stroke
				(width 0.1)
				(type default)
			)
			(layer "B.Fab")
		)
		(pad "1" smd circle
			(at 0.40005 0)
			(size 0 0)
			(layers "B.Cu" "B.Mask" "B.Paste")
			(net "P3V3_AUX")
		)
		(pad "2" smd circle
			(at -0.40005 0)
			(size 0 0)
			(layers "B.Cu" "B.Mask" "B.Paste")
			(net "GND")
		)
	)
	(footprint ""
		(layer "B.Cu")
		(at 420.285418 -193.353436 -90)
		(property "Reference" "R708"
			(at 0 0 90)
			(layer "B.SilkS")
			(hide yes)
			(effects
				(font
					(size 1.27 1.27)
				)
				(justify mirror)
			)
		)
		(property "Value" ""
			(at 0 0 90)
			(layer "B.Fab")
			(effects
				(font
					(size 1.27 1.27)
				)
				(justify mirror)
			)
		)
		(duplicate_pad_numbers_are_jumpers no)
		(fp_line
			(start -0.7874 0.4064)
			(end 0.7874 0.4064)
			(stroke
				(width 0.1524)
				(type default)
			)
			(layer "B.SilkS")
		)
		(fp_line
			(start 0.7874 0.4064)
			(end 0.7874 -0.4064)
			(stroke
				(width 0.1524)
				(type default)
			)
			(layer "B.SilkS")
		)
		(fp_line
			(start -0.7874 -0.4064)
			(end -0.7874 0.4064)
			(stroke
				(width 0.1524)
				(type default)
			)
			(layer "B.SilkS")
		)
		(fp_line
			(start 0.7874 -0.4064)
			(end -0.7874 -0.4064)
			(stroke
				(width 0.1524)
				(type default)
			)
			(layer "B.SilkS")
		)
		(fp_line
			(start -0.67945 0.3048)
			(end -0.120396 0.3048)
			(stroke
				(width 0.1)
				(type default)
			)
			(layer "B.Fab")
		)
		(fp_line
			(start -0.120396 0.3048)
			(end -0.120396 0.2794)
			(stroke
				(width 0.1)
				(type default)
			)
			(layer "B.Fab")
		)
		(fp_line
			(start 0.12065 0.3048)
			(end 0.67945 0.3048)
			(stroke
				(width 0.1)
				(type default)
			)
			(layer "B.Fab")
		)
		(fp_line
			(start 0.67945 0.3048)
			(end 0.67945 -0.305054)
			(stroke
				(width 0.1)
				(type default)
			)
			(layer "B.Fab")
		)
		(fp_line
			(start -0.120396 0.2794)
			(end 0.12065 0.2794)
			(stroke
				(width 0.1)
				(type default)
			)
			(layer "B.Fab")
		)
		(fp_line
			(start 0.12065 0.2794)
			(end 0.12065 0.3048)
			(stroke
				(width 0.1)
				(type default)
			)
			(layer "B.Fab")
		)
		(fp_line
			(start -0.12065 -0.2794)
			(end -0.12065 -0.3048)
			(stroke
				(width 0.1)
				(type default)
			)
			(layer "B.Fab")
		)
		(fp_line
			(start 0.12065 -0.2794)
			(end -0.12065 -0.2794)
			(stroke
				(width 0.1)
				(type default)
			)
			(layer "B.Fab")
		)
		(fp_line
			(start -0.67945 -0.3048)
			(end -0.67945 0.3048)
			(stroke
				(width 0.1)
				(type default)
			)
			(layer "B.Fab")
		)
		(fp_line
			(start -0.12065 -0.3048)
			(end -0.67945 -0.3048)
			(stroke
				(width 0.1)
				(type default)
			)
			(layer "B.Fab")
		)
		(fp_line
			(start 0.12065 -0.305054)
			(end 0.12065 -0.2794)
			(stroke
				(width 0.1)
				(type default)
			)
			(layer "B.Fab")
		)
		(fp_line
			(start 0.67945 -0.305054)
			(end 0.12065 -0.305054)
			(stroke
				(width 0.1)
				(type default)
			)
			(layer "B.Fab")
		)
		(pad "1" smd circle
			(at 0.40005 0 90)
			(size 0 0)
			(layers "B.Cu" "B.Mask" "B.Paste")
			(net "RST_PLD_CPU0_DRAM_EF_N")
		)
		(pad "2" smd circle
			(at -0.40005 0 90)
			(size 0 0)
			(layers "B.Cu" "B.Mask" "B.Paste")
			(net "GND")
		)
	)
)
